FILE_TYPE = CONNECTIVITY;
{Allegro Design Entry HDL 17.2-2016 S081 (4005846) 1/11/2022}
"PAGE_NUMBER" = 60;
0"NC";
1"T_GND\g";
2"T_GND\g";
3"T_GND\g";
4"T_GND\g";
5"T_GND\g";
6"T_GND\g";
7"GND_P1\g";
8"GND_P1\g";
9"GND_P1\g";
10"GND_P1\g";
11"GND_P1\g";
12"GND_P1\g";
13"GND_P1\g";
14"GND_P1\g";
15"GND_P1\g";
16"GND_P1\g";
17"GND_P1\g";
18"GND_P1\g";
19"GND_P1\g";
20"GND_P1\g";
21"GND_P1\g";
22"GND_P1\g";
23"TDR_SE_50_OHM_IN2";
24"TDR_SE_50_OHM_IN1";
25"TDR_DIFF_85_BOT_DP";
26"TDR_DIFF_85_BOT_DN";
27"TDR_DIFF_85_IN4_DP";
28"TDR_DIFF_85_IN4_DN";
29"TDR_DIFF_85_TOP_DP";
30"TDR_DIFF_85_TOP_DN";
31"TDR_DIFF_100_BOT_DP";
32"TDR_DIFF_100_BOT_DN";
33"TDR_DIFF_100_IN4_DP";
34"TDR_DIFF_100_IN4_DN";
35"TDR_DIFF_100_IN1_DP";
36"TDR_DIFF_100_IN1_DN";
37"TDR_DIFF_100_TOP_DN";
38"TDR_DIFF_100_TOP_DP";
39"TDR_SE_50_OHM_IN3";
40"TDR_SE_50_OHM_TOP";
41"TDR_SE_50_OHM_BOT";
42"TDR_SE_50_OHM_IN4";
43"TDR_DIFF_85_IN1_DP";
44"TDR_DIFF_85_IN1_DN";
%"TDR_3P"
"2","(-8500,5700)","0","pure_quanta","I1";
;
PACK_TYPE"TH2"
CDS_LMAN_SYM_OUTLINE"-150,100,50,-100"
CDS_LIB"pure_quanta"
PART_NUMBER"N_A"
MATERIAL"EMPTY"
SEC_TYPE"TH2"
LOCATION"DB1"
SEC"1";
"IO2 \B"
$PN"3"40;
"IO1 \B"
$PN"2"40;
"GND"
$PN"1"1;
%"UNIVERSAL_GND"
"1","(-8975,4475)","0","logical_power","I10";
;
HDL_POWER"T_GND"
CDS_LIB"logical_power";
"A"3;
%"TDR_3P"
"2","(-8500,5225)","0","pure_quanta","I11";
;
PACK_TYPE"TH2"
CDS_LMAN_SYM_OUTLINE"-150,100,50,-100"
CDS_LIB"pure_quanta"
PART_NUMBER"N_A"
MATERIAL"EMPTY"
SEC_TYPE"TH2"
LOCATION"DB2"
SEC"1";
"IO2 \B"
$PN"3"24;
"IO1 \B"
$PN"2"24;
"GND"
$PN"1"2;
%"UNIVERSAL_GND"
"1","(-8975,4950)","0","logical_power","I12";
;
HDL_POWER"T_GND"
CDS_LIB"logical_power";
"A"2;
%"TP_TDR_4P_FTS"
"1","(-6450,5700)","0","pure_quanta","I13";
;
PACK_TYPE"TH"
MATERIAL"EMPTY"
VALUE"TP_TDR_4P_DIP"
PART_NUMBER"TP15"
SEC_TYPE"TH"
CDS_LIB"pure_quanta"
NEEDS_NO_SIZE"TRUE"
LOCATION"X1"
SEC"1";
"S1"
$PN"1"29;
"P2 \B"
$PN"3"8;
"S2"
$PN"4"30;
"P1 \B"
$PN"2"8;
%"TP_TDR_4P_FTS"
"1","(-4925,5700)","4","pure_quanta","I14";
;
PACK_TYPE"TH"
MATERIAL"EMPTY"
PART_NUMBER"TP15"
VALUE"TP_TDR_4P_DIP"
NEEDS_NO_SIZE"TRUE"
CDS_LIB"pure_quanta"
SEC_TYPE"TH"
LOCATION"X7"
SEC"1";
"S1"
$PN"1"30;
"P2 \B"
$PN"3"9;
"S2"
$PN"4"29;
"P1 \B"
$PN"2"9;
%"TP_TDR_4P_FTS"
"1","(-4925,2200)","4","pure_quanta","I18";
;
PART_NUMBER"TP15"
VALUE"TP_TDR_4P_DIP"
MATERIAL"EMPTY"
PACK_TYPE"TH"
SEC_TYPE"TH"
CDS_LIB"pure_quanta"
NEEDS_NO_SIZE"TRUE"
LOCATION"X12"
SEC"1";
"S1"
$PN"1"26;
"P2 \B"
$PN"3"19;
"S2"
$PN"4"25;
"P1 \B"
$PN"2"19;
%"TP_TDR_4P_FTS"
"1","(-6450,2200)","0","pure_quanta","I19";
;
PART_NUMBER"TP15"
VALUE"TP_TDR_4P_DIP"
MATERIAL"EMPTY"
PACK_TYPE"TH"
NEEDS_NO_SIZE"TRUE"
CDS_LIB"pure_quanta"
SEC_TYPE"TH"
LOCATION"X6"
SEC"1";
"S1"
$PN"1"25;
"P2 \B"
$PN"3"20;
"S2"
$PN"4"26;
"P1 \B"
$PN"2"20;
%"UNIVERSAL_GND"
"1","(-8975,5425)","0","logical_power","I2";
;
HDL_POWER"T_GND"
CDS_LIB"logical_power";
"A"1;
%"TP_TDR_4P_FTS"
"1","(-4925,2900)","4","pure_quanta","I22";
;
PART_NUMBER"TP15"
VALUE"TP_TDR_4P_DIP"
MATERIAL"EMPTY"
PACK_TYPE"TH"
SEC_TYPE"TH"
CDS_LIB"pure_quanta"
NEEDS_NO_SIZE"TRUE"
LOCATION"X11"
SEC"1";
"S1"
$PN"1"28;
"P2 \B"
$PN"3"22;
"S2"
$PN"4"27;
"P1 \B"
$PN"2"22;
%"TP_TDR_4P_FTS"
"1","(-6450,2900)","0","pure_quanta","I23";
;
PART_NUMBER"TP15"
VALUE"TP_TDR_4P_DIP"
MATERIAL"EMPTY"
PACK_TYPE"TH"
NEEDS_NO_SIZE"TRUE"
CDS_LIB"pure_quanta"
SEC_TYPE"TH"
LOCATION"X5"
SEC"1";
"S1"
$PN"1"27;
"P2 \B"
$PN"3"21;
"S2"
$PN"4"28;
"P1 \B"
$PN"2"21;
%"TDR_3P"
"2","(-8500,3325)","0","pure_quanta","I3";
;
PACK_TYPE"TH2"
CDS_LMAN_SYM_OUTLINE"-150,100,50,-100"
CDS_LIB"pure_quanta"
PART_NUMBER"N_A"
MATERIAL"EMPTY"
SEC_TYPE"TH2"
LOCATION"DB6"
SEC"1";
"IO2 \B"
$PN"3"41;
"IO1 \B"
$PN"2"41;
"GND"
$PN"1"5;
%"TP_TDR_4P_FTS"
"1","(-4925,5000)","4","pure_quanta","I34";
;
PART_NUMBER"TP15"
VALUE"TP_TDR_4P_DIP"
MATERIAL"EMPTY"
PACK_TYPE"TH"
SEC_TYPE"TH"
CDS_LIB"pure_quanta"
NEEDS_NO_SIZE"TRUE"
LOCATION"X8"
SEC"1";
"S1"
$PN"1"44;
"P2 \B"
$PN"3"10;
"S2"
$PN"4"43;
"P1 \B"
$PN"2"10;
%"TP_TDR_4P_FTS"
"1","(-6450,5000)","0","pure_quanta","I35";
;
PART_NUMBER"TP15"
VALUE"TP_TDR_4P_DIP"
MATERIAL"EMPTY"
PACK_TYPE"TH"
NEEDS_NO_SIZE"TRUE"
CDS_LIB"pure_quanta"
SEC_TYPE"TH"
LOCATION"X2"
SEC"1";
"S1"
$PN"1"43;
"P2 \B"
$PN"3"7;
"S2"
$PN"4"44;
"P1 \B"
$PN"2"7;
%"TP_TDR_4P_FTS"
"1","(-1800,5700)","4","pure_quanta","I38";
;
PART_NUMBER"TP15"
VALUE"TP_TDR_4P_DIP"
MATERIAL"EMPTY"
PACK_TYPE"TH"
SEC_TYPE"TH"
CDS_LIB"pure_quanta"
NEEDS_NO_SIZE"TRUE"
LOCATION"X19"
SEC"1";
"S1"
$PN"1"37;
"P2 \B"
$PN"3"12;
"S2"
$PN"4"38;
"P1 \B"
$PN"2"12;
%"TP_TDR_4P_FTS"
"1","(-3325,5700)","0","pure_quanta","I39";
;
PART_NUMBER"TP15"
MATERIAL"EMPTY"
PACK_TYPE"TH"
VALUE"TP_TDR_4P_DIP"
NEEDS_NO_SIZE"TRUE"
CDS_LIB"pure_quanta"
SEC_TYPE"TH"
LOCATION"X13"
SEC"1";
"S1"
$PN"1"38;
"P2 \B"
$PN"3"13;
"S2"
$PN"4"37;
"P1 \B"
$PN"2"13;
%"UNIVERSAL_GND"
"1","(-8975,3050)","0","logical_power","I4";
;
HDL_POWER"T_GND"
CDS_LIB"logical_power";
"A"5;
%"TP_TDR_4P_FTS"
"1","(-3325,2200)","0","pure_quanta","I42";
;
PACK_TYPE"TH"
MATERIAL"EMPTY"
VALUE"TP_TDR_4P_DIP"
PART_NUMBER"TP15"
SEC_TYPE"TH"
CDS_LIB"pure_quanta"
NEEDS_NO_SIZE"TRUE"
LOCATION"X18"
SEC"1";
"S1"
$PN"1"31;
"P2 \B"
$PN"3"17;
"S2"
$PN"4"32;
"P1 \B"
$PN"2"17;
%"TP_TDR_4P_FTS"
"1","(-1800,2200)","4","pure_quanta","I43";
;
PACK_TYPE"TH"
MATERIAL"EMPTY"
VALUE"TP_TDR_4P_DIP"
PART_NUMBER"TP15"
NEEDS_NO_SIZE"TRUE"
CDS_LIB"pure_quanta"
SEC_TYPE"TH"
LOCATION"X24"
SEC"1";
"S1"
$PN"1"32;
"P2 \B"
$PN"3"18;
"S2"
$PN"4"31;
"P1 \B"
$PN"2"18;
%"TP_TDR_4P_FTS"
"1","(-3325,2900)","0","pure_quanta","I46";
;
PACK_TYPE"TH"
MATERIAL"EMPTY"
VALUE"TP_TDR_4P_DIP"
PART_NUMBER"TP15"
SEC_TYPE"TH"
CDS_LIB"pure_quanta"
NEEDS_NO_SIZE"TRUE"
LOCATION"X17"
SEC"1";
"S1"
$PN"1"33;
"P2 \B"
$PN"3"16;
"S2"
$PN"4"34;
"P1 \B"
$PN"2"16;
%"TP_TDR_4P_FTS"
"1","(-1800,2900)","4","pure_quanta","I47";
;
PACK_TYPE"TH"
MATERIAL"EMPTY"
VALUE"TP_TDR_4P_DIP"
PART_NUMBER"TP15"
NEEDS_NO_SIZE"TRUE"
CDS_LIB"pure_quanta"
SEC_TYPE"TH"
LOCATION"X23"
SEC"1";
"S1"
$PN"1"34;
"P2 \B"
$PN"3"15;
"S2"
$PN"4"33;
"P1 \B"
$PN"2"15;
%"TDR_3P"
"2","(-8500,3800)","0","pure_quanta","I5";
;
PACK_TYPE"TH2"
CDS_LMAN_SYM_OUTLINE"-150,100,50,-100"
CDS_LIB"pure_quanta"
PART_NUMBER"N_A"
MATERIAL"EMPTY"
SEC_TYPE"TH2"
LOCATION"DB5"
SEC"1";
"IO2 \B"
$PN"3"42;
"IO1 \B"
$PN"2"42;
"GND"
$PN"1"6;
%"TP_TDR_4P_FTS"
"1","(-3325,5000)","0","pure_quanta","I58";
;
PACK_TYPE"TH"
VALUE"TP_TDR_4P_DIP"
PART_NUMBER"TP15"
MATERIAL"EMPTY"
SEC_TYPE"TH"
CDS_LIB"pure_quanta"
NEEDS_NO_SIZE"TRUE"
LOCATION"X14"
SEC"1";
"S1"
$PN"1"35;
"P2 \B"
$PN"3"11;
"S2"
$PN"4"36;
"P1 \B"
$PN"2"11;
%"TP_TDR_4P_FTS"
"1","(-1800,5000)","4","pure_quanta","I59";
;
PACK_TYPE"TH"
MATERIAL"EMPTY"
VALUE"TP_TDR_4P_DIP"
PART_NUMBER"TP15"
NEEDS_NO_SIZE"TRUE"
CDS_LIB"pure_quanta"
SEC_TYPE"TH"
LOCATION"X20"
SEC"1";
"S1"
$PN"1"36;
"P2 \B"
$PN"3"14;
"S2"
$PN"4"35;
"P1 \B"
$PN"2"14;
%"UNIVERSAL_GND"
"1","(-8975,3525)","0","logical_power","I6";
;
HDL_POWER"T_GND"
CDS_LIB"logical_power";
"A"6;
%"UNIVERSAL_GND"
"1","(-6850,4700)","0","logical_power","I61";
;
HDL_POWER"GND_P1"
CDS_LIB"logical_power";
"A"7;
%"UNIVERSAL_GND"
"1","(-6850,5400)","0","logical_power","I62";
;
HDL_POWER"GND_P1"
CDS_LIB"logical_power";
"A"8;
%"UNIVERSAL_GND"
"1","(-4550,5400)","0","logical_power","I63";
;
HDL_POWER"GND_P1"
CDS_LIB"logical_power";
"A"9;
%"UNIVERSAL_GND"
"1","(-4550,4700)","0","logical_power","I64";
;
HDL_POWER"GND_P1"
CDS_LIB"logical_power";
"A"10;
%"UNIVERSAL_GND"
"1","(-3725,4700)","0","logical_power","I65";
;
HDL_POWER"GND_P1"
CDS_LIB"logical_power";
"A"11;
%"UNIVERSAL_GND"
"1","(-1425,4700)","0","logical_power","I66";
;
HDL_POWER"GND_P1"
CDS_LIB"logical_power";
"A"14;
%"UNIVERSAL_GND"
"1","(-1425,5400)","0","logical_power","I67";
;
HDL_POWER"GND_P1"
CDS_LIB"logical_power";
"A"12;
%"UNIVERSAL_GND"
"1","(-3725,5400)","0","logical_power","I68";
;
HDL_POWER"GND_P1"
CDS_LIB"logical_power";
"A"13;
%"UNIVERSAL_GND"
"1","(-1425,2600)","0","logical_power","I69";
;
HDL_POWER"GND_P1"
CDS_LIB"logical_power";
"A"15;
%"TDR_3P"
"2","(-8500,4275)","0","pure_quanta","I7";
;
PACK_TYPE"TH2"
CDS_LMAN_SYM_OUTLINE"-150,100,50,-100"
CDS_LIB"pure_quanta"
PART_NUMBER"N_A"
MATERIAL"EMPTY"
SEC_TYPE"TH2"
LOCATION"DB4"
SEC"1";
"IO2 \B"
$PN"3"39;
"IO1 \B"
$PN"2"39;
"GND"
$PN"1"4;
%"UNIVERSAL_GND"
"1","(-3725,2600)","0","logical_power","I70";
;
HDL_POWER"GND_P1"
CDS_LIB"logical_power";
"A"16;
%"UNIVERSAL_GND"
"1","(-3725,1900)","0","logical_power","I71";
;
HDL_POWER"GND_P1"
CDS_LIB"logical_power";
"A"17;
%"UNIVERSAL_GND"
"1","(-1425,1900)","0","logical_power","I72";
;
HDL_POWER"GND_P1"
CDS_LIB"logical_power";
"A"18;
%"UNIVERSAL_GND"
"1","(-4550,1900)","0","logical_power","I73";
;
HDL_POWER"GND_P1"
CDS_LIB"logical_power";
"A"19;
%"UNIVERSAL_GND"
"1","(-6850,1900)","0","logical_power","I74";
;
HDL_POWER"GND_P1"
CDS_LIB"logical_power";
"A"20;
%"UNIVERSAL_GND"
"1","(-6850,2600)","0","logical_power","I75";
;
HDL_POWER"GND_P1"
CDS_LIB"logical_power";
"A"21;
%"UNIVERSAL_GND"
"1","(-4550,2600)","0","logical_power","I76";
;
HDL_POWER"GND_P1"
CDS_LIB"logical_power";
"A"22;
%"UNIVERSAL_GND"
"1","(-8975,4000)","0","logical_power","I8";
;
HDL_POWER"T_GND"
CDS_LIB"logical_power";
"A"4;
%"TDR_3P"
"2","(-8500,4750)","0","pure_quanta","I9";
;
PACK_TYPE"TH2"
CDS_LMAN_SYM_OUTLINE"-150,100,50,-100"
CDS_LIB"pure_quanta"
PART_NUMBER"N_A"
MATERIAL"EMPTY"
SEC_TYPE"TH2"
LOCATION"DB3"
SEC"1";
"IO2 \B"
$PN"3"23;
"IO1 \B"
$PN"2"23;
"GND"
$PN"1"3;
END.
